# T6G (Grand Teton) — schematic netlist excerpt (pin names and nets, part order shuffled) for the footprints in the layout excerpt that follows; sources: Cadence DE-HDL packaged netlist, KiCad conversion of 04192023_DAF0TMB3IC0_F0TG_MB_C_brd_V02_OCP.brd

Q67  MOSFET_NCH_DUAL  PJT138K IC  pkg SOT363XD  page 127
  S1  = GND
  G1  = BIC_MONITER
  D2  = BIC_MONITER_ISO
  S2  = GND
  G2  = BIC_MONITER_N
  D1  = BIC_MONITER_N

U236  PCA9617ADP  IC  pkg TSSOP8_3XB  page 247
  VCCA  = P3V3_AUX
  SCLA  = SMB_OCP_SFF_3V3AUX_SCL
  SDAA  = SMB_OCP_SFF_3V3AUX_SDA
  GND  = GND
  EN  = HP_LVC3_OCP_V3_1_R_EN
  SDAB  = SMB_OCP_SFF_3V3AUX_BUF_SDA
  SCLB  = SMB_OCP_SFF_3V3AUX_BUF_SCL
  VCCB  = P3V3_OCP_SFF

(kicad_pcb
	(version 20260206)
	(generator "pcbnew")
	(generator_version "10.0")
	(general
		(thickness 1.6)
		(legacy_teardrops no)
	)
	(paper "A4")
	(title_block
		(title "04192023_DAF0TMB3IC0_F0TG_MB_C_brd_V02_OCP.brd")
		(comment 1 "Grand Teton / footprints 2539-2540 of 8354")
	)
	(layers
		(0 "F.Cu" signal "TOP")
		(4 "In1.Cu" signal "GND")
		(6 "In2.Cu" signal "IN1")
		(8 "In3.Cu" signal "GND1")
		(10 "In4.Cu" signal "IN2")
		(12 "In5.Cu" signal "GND2")
		(14 "In6.Cu" signal "IN3")
		(16 "In7.Cu" signal "GND3")
		(18 "In8.Cu" signal "VCC")
		(20 "In9.Cu" signal "VCC1")
		(22 "In10.Cu" signal "GND4")
		(24 "In11.Cu" signal "IN4")
		(26 "In12.Cu" signal "GND5")
		(28 "In13.Cu" signal "IN5")
		(30 "In14.Cu" signal "GND6")
		(32 "In15.Cu" signal "IN6")
		(34 "In16.Cu" signal "GND7")
		(2 "B.Cu" signal "BOTTOM")
		(9 "F.Adhes" user "F.Adhesive")
		(11 "B.Adhes" user "B.Adhesive")
		(13 "F.Paste" user "Package Geometry/Pastemask Top")
		(15 "B.Paste" user "Package Geometry/Pastemask Bottom")
		(5 "F.SilkS" user "Ref Des/Silkscreen Top")
		(7 "B.SilkS" user "Ref Des/Silkscreen Bottom")
		(1 "F.Mask" user "Board Geometry/Soldermask Top")
		(3 "B.Mask" user "Board Geometry/Soldermask Bottom")
		(17 "Dwgs.User" user "User.Drawings")
		(19 "Cmts.User" user "User.Comments")
		(21 "Eco1.User" user "User.Eco1")
		(23 "Eco2.User" user "User.Eco2")
		(25 "Edge.Cuts" user "Board Geometry/Outline")
		(27 "Margin" user)
		(31 "F.CrtYd" user "Package Geometry/Place Bound Top")
		(29 "B.CrtYd" user "Package Geometry/Place Bound Bottom")
		(35 "F.Fab" user "Ref Des/Assembly Top")
		(33 "B.Fab" user "Ref Des/Assembly Bottom")
	)
	(footprint ""
		(layer "F.Cu")
		(at 167.871902 -439.490358)
		(property "Reference" "Q67"
			(at 3.377184 1.185672 0)
			(unlocked yes)
			(layer "F.SilkS")
			(effects
				(font
					(size 0.7874 0.5842)
					(thickness 0.1524)
				)
				(justify left)
			)
		)
		(property "Value" ""
			(at 0 0 0)
			(layer "F.Fab")
			(effects
				(font
					(size 1.27 1.27)
				)
			)
		)
		(duplicate_pad_numbers_are_jumpers no)
		(fp_line
			(start -1.332738 -1.100074)
			(end -0.4826 -1.100074)
			(stroke
				(width 0.1524)
				(type default)
			)
			(layer "F.SilkS")
		)
		(fp_line
			(start -1.332738 1.100074)
			(end -1.332738 -1.100074)
			(stroke
				(width 0.1524)
				(type default)
			)
			(layer "F.SilkS")
		)
		(fp_line
			(start -0.4826 -1.100074)
			(end 0 -0.541274)
			(stroke
				(width 0.1524)
				(type default)
			)
			(layer "F.SilkS")
		)
		(fp_line
			(start 0 -0.541274)
			(end 0.4826 -1.100074)
			(stroke
				(width 0.1524)
				(type default)
			)
			(layer "F.SilkS")
		)
		(fp_line
			(start 0.4826 -1.100074)
			(end 1.332738 -1.100074)
			(stroke
				(width 0.1524)
				(type default)
			)
			(layer "F.SilkS")
		)
		(fp_line
			(start 1.332738 -1.100074)
			(end 1.332738 1.100074)
			(stroke
				(width 0.1524)
				(type default)
			)
			(layer "F.SilkS")
		)
		(fp_line
			(start 1.332738 1.100074)
			(end -1.332738 1.100074)
			(stroke
				(width 0.1524)
				(type default)
			)
			(layer "F.SilkS")
		)
		(fp_poly
			(pts
				(xy -1.561592 -1.409192) (xy -2.337308 -1.52908) (xy -1.930908 -2.101596)
			)
			(stroke
				(width 0)
				(type default)
			)
			(fill yes)
			(layer "F.SilkS")
		)
		(fp_line
			(start -0.674878 -1.100074)
			(end 0.674878 -1.100074)
			(stroke
				(width 0.1)
				(type default)
			)
			(layer "F.Fab")
		)
		(fp_line
			(start -0.674878 1.100074)
			(end -0.674878 -1.100074)
			(stroke
				(width 0.1)
				(type default)
			)
			(layer "F.Fab")
		)
		(fp_line
			(start 0.674878 -1.100074)
			(end 0.674878 1.100074)
			(stroke
				(width 0.1)
				(type default)
			)
			(layer "F.Fab")
		)
		(fp_line
			(start 0.674878 1.100074)
			(end -0.674878 1.100074)
			(stroke
				(width 0.1)
				(type default)
			)
			(layer "F.Fab")
		)
		(fp_poly
			(pts
				(xy -2.2352 -0.298958) (xy -2.2352 -1.001014) (xy -1.533144 -0.649986)
			)
			(stroke
				(width 0)
				(type default)
			)
			(fill yes)
			(layer "F.Fab")
		)
		(pad "1" smd rect
			(at -0.94996 -0.649986 90)
			(size 0.4318 0.508)
			(layers "F.Cu" "F.Mask" "F.Paste")
			(net "GND")
		)
		(pad "2" smd rect
			(at -0.94996 0 90)
			(size 0.4318 0.508)
			(layers "F.Cu" "F.Mask" "F.Paste")
			(net "BIC_MONITER")
		)
		(pad "3" smd rect
			(at -0.94996 0.649986 90)
			(size 0.4318 0.508)
			(layers "F.Cu" "F.Mask" "F.Paste")
			(net "BIC_MONITER_ISO")
		)
		(pad "4" smd rect
			(at 0.94996 0.649986 90)
			(size 0.4318 0.508)
			(layers "F.Cu" "F.Mask" "F.Paste")
			(net "GND")
		)
		(pad "5" smd rect
			(at 0.94996 0 90)
			(size 0.4318 0.508)
			(layers "F.Cu" "F.Mask" "F.Paste")
			(net "BIC_MONITER_N")
		)
		(pad "6" smd rect
			(at 0.94996 -0.649986 90)
			(size 0.4318 0.508)
			(layers "F.Cu" "F.Mask" "F.Paste")
			(net "BIC_MONITER_N")
		)
	)
	(footprint ""
		(layer "F.Cu")
		(at 407.1874 -76.063348)
		(property "Reference" "U236"
			(at -3.0988 -2.885948 0)
			(unlocked yes)
			(layer "F.SilkS")
			(effects
				(font
					(size 0.7874 0.5842)
					(thickness 0.1524)
				)
				(justify left)
			)
		)
		(property "Value" ""
			(at 0 0 0)
			(layer "F.Fab")
			(effects
				(font
					(size 1.27 1.27)
				)
			)
		)
		(duplicate_pad_numbers_are_jumpers no)
		(fp_line
			(start -1.463548 -1.549908)
			(end -0.787908 -1.549908)
			(stroke
				(width 0.1524)
				(type default)
			)
			(layer "F.SilkS")
		)
		(fp_line
			(start -1.463548 1.549908)
			(end -1.463548 -1.549908)
			(stroke
				(width 0.1524)
				(type default)
			)
			(layer "F.SilkS")
		)
		(fp_line
			(start -0.787908 -1.549908)
			(end -0.0254 -0.7874)
			(stroke
				(width 0.1524)
				(type default)
			)
			(layer "F.SilkS")
		)
		(fp_line
			(start -0.0254 1.549908)
			(end -1.463548 1.549908)
			(stroke
				(width 0.1524)
				(type default)
			)
			(layer "F.SilkS")
		)
		(fp_line
			(start 1.0922 -1.549908)
			(end 1.463548 -1.549908)
			(stroke
				(width 0.1524)
				(type default)
			)
			(layer "F.SilkS")
		)
		(fp_line
			(start 1.463548 -1.549908)
			(end 1.463548 1.549908)
			(stroke
				(width 0.1524)
				(type default)
			)
			(layer "F.SilkS")
		)
		(fp_line
			(start 1.463548 1.549908)
			(end 1.0922 1.549908)
			(stroke
				(width 0.1524)
				(type default)
			)
			(layer "F.SilkS")
		)
		(fp_poly
			(pts
				(xy -2.623566 -2.194306) (xy -2.00406 -2.205482) (xy -2.30251 -1.580134)
			)
			(stroke
				(width 0)
				(type default)
			)
			(fill yes)
			(layer "F.SilkS")
		)
		(fp_line
			(start -1.549908 -1.549908)
			(end 1.549908 -1.549908)
			(stroke
				(width 0.1)
				(type default)
			)
			(layer "F.Fab")
		)
		(fp_line
			(start -1.549908 1.549908)
			(end -1.549908 -1.549908)
			(stroke
				(width 0.1)
				(type default)
			)
			(layer "F.Fab")
		)
		(fp_line
			(start 1.549908 -1.549908)
			(end 1.549908 1.549908)
			(stroke
				(width 0.1)
				(type default)
			)
			(layer "F.Fab")
		)
		(fp_line
			(start 1.549908 1.549908)
			(end -1.549908 1.549908)
			(stroke
				(width 0.1)
				(type default)
			)
			(layer "F.Fab")
		)
		(fp_poly
			(pts
				(xy -3.4798 -1.359916) (xy -2.86004 -1.050036) (xy -3.4798 -0.740156)
			)
			(stroke
				(width 0)
				(type default)
			)
			(fill yes)
			(layer "F.Fab")
		)
		(pad "1" smd rect
			(at -2.175002 -1.050036 90)
			(size 0.6096 1.1684)
			(layers "F.Cu" "F.Mask" "F.Paste")
			(net "P3V3_AUX")
		)
		(pad "2" smd rect
			(at -2.175002 -0.32512 90)
			(size 0.4318 1.1684)
			(layers "F.Cu" "F.Mask" "F.Paste")
			(net "SMB_OCP_SFF_3V3AUX_SCL")
		)
		(pad "3" smd rect
			(at -2.175002 0.32512 90)
			(size 0.4318 1.1684)
			(layers "F.Cu" "F.Mask" "F.Paste")
			(net "SMB_OCP_SFF_3V3AUX_SDA")
		)
		(pad "4" smd rect
			(at -2.175002 1.050036 90)
			(size 0.6096 1.1684)
			(layers "F.Cu" "F.Mask" "F.Paste")
			(net "GND")
		)
		(pad "5" smd rect
			(at 2.175002 1.050036 90)
			(size 0.6096 1.1684)
			(layers "F.Cu" "F.Mask" "F.Paste")
			(net "HP_LVC3_OCP_V3_1_R_EN")
		)
		(pad "6" smd rect
			(at 2.175002 0.32512 90)
			(size 0.4318 1.1684)
			(layers "F.Cu" "F.Mask" "F.Paste")
			(net "SMB_OCP_SFF_3V3AUX_BUF_SDA")
		)
		(pad "7" smd rect
			(at 2.175002 -0.32512 90)
			(size 0.4318 1.1684)
			(layers "F.Cu" "F.Mask" "F.Paste")
			(net "SMB_OCP_SFF_3V3AUX_BUF_SCL")
		)
		(pad "8" smd rect
			(at 2.175002 -1.050036 90)
			(size 0.6096 1.1684)
			(layers "F.Cu" "F.Mask" "F.Paste")
			(net "P3V3_OCP_SFF")
		)
	)
)
